G04 #@! TF.GenerationSoftware,KiCad,Pcbnew,(5.0.1)-3*
G04 #@! TF.CreationDate,2019-04-10T15:36:06+02:00*
G04 #@! TF.ProjectId,discovery,646973636F766572792E6B696361645F,rev?*
G04 #@! TF.SameCoordinates,PX4c4640PY8a48028*
G04 #@! TF.FileFunction,Soldermask,Bot*
G04 #@! TF.FilePolarity,Negative*
%FSLAX46Y46*%
G04 Gerber Fmt 4.6, Leading zero omitted, Abs format (unit mm)*
%MOMM*%
%LPD*%
G01*
G04 APERTURE LIST*
%ADD10C,0.100000*%
G04 APERTURE END LIST*
D10*
G36*
X140745376Y2451407D02*
X140745378Y2451406D01*
X140745379Y2451406D01*
X141209632Y2259107D01*
X141625564Y1981190D01*
X141627451Y1979929D01*
X141982769Y1624611D01*
X141982771Y1624608D01*
X142261947Y1206792D01*
X142454246Y742539D01*
X142552280Y249692D01*
X142552280Y-252812D01*
X142454246Y-745659D01*
X142261947Y-1209912D01*
X141984030Y-1625844D01*
X141982769Y-1627731D01*
X141627451Y-1983049D01*
X141627448Y-1983051D01*
X141209632Y-2262227D01*
X140745379Y-2454526D01*
X140745378Y-2454526D01*
X140745376Y-2454527D01*
X140252533Y-2552560D01*
X139750027Y-2552560D01*
X139257184Y-2454527D01*
X139257182Y-2454526D01*
X139257181Y-2454526D01*
X138792928Y-2262227D01*
X138375112Y-1983051D01*
X138375109Y-1983049D01*
X138019791Y-1627731D01*
X138018530Y-1625844D01*
X137740613Y-1209912D01*
X137548314Y-745659D01*
X137450280Y-252812D01*
X137450280Y249692D01*
X137548314Y742539D01*
X137740613Y1206792D01*
X138019789Y1624608D01*
X138019791Y1624611D01*
X138375109Y1979929D01*
X138376996Y1981190D01*
X138792928Y2259107D01*
X139257181Y2451406D01*
X139257182Y2451406D01*
X139257184Y2451407D01*
X139750027Y2549440D01*
X140252533Y2549440D01*
X140745376Y2451407D01*
X140745376Y2451407D01*
G37*
G36*
X745376Y2451407D02*
X745378Y2451406D01*
X745379Y2451406D01*
X1209632Y2259107D01*
X1625564Y1981190D01*
X1627451Y1979929D01*
X1982769Y1624611D01*
X1982771Y1624608D01*
X2261947Y1206792D01*
X2454246Y742539D01*
X2552280Y249692D01*
X2552280Y-252812D01*
X2454246Y-745659D01*
X2261947Y-1209912D01*
X1984030Y-1625844D01*
X1982769Y-1627731D01*
X1627451Y-1983049D01*
X1627448Y-1983051D01*
X1209632Y-2262227D01*
X745379Y-2454526D01*
X745378Y-2454526D01*
X745376Y-2454527D01*
X252533Y-2552560D01*
X-249973Y-2552560D01*
X-742816Y-2454527D01*
X-742818Y-2454526D01*
X-742819Y-2454526D01*
X-1207072Y-2262227D01*
X-1624888Y-1983051D01*
X-1624891Y-1983049D01*
X-1980209Y-1627731D01*
X-1981470Y-1625844D01*
X-2259387Y-1209912D01*
X-2451686Y-745659D01*
X-2549720Y-252812D01*
X-2549720Y249692D01*
X-2451686Y742539D01*
X-2259387Y1206792D01*
X-1980211Y1624608D01*
X-1980209Y1624611D01*
X-1624891Y1979929D01*
X-1623004Y1981190D01*
X-1207072Y2259107D01*
X-742819Y2451406D01*
X-742818Y2451406D01*
X-742816Y2451407D01*
X-249973Y2549440D01*
X252533Y2549440D01*
X745376Y2451407D01*
X745376Y2451407D01*
G37*
G36*
X57203825Y17759260D02*
X58578018Y17190050D01*
X58578020Y17190049D01*
X59787209Y16382095D01*
X59814765Y16363683D01*
X60866523Y15311925D01*
X60866525Y15311922D01*
X61432527Y14464840D01*
X61692890Y14075178D01*
X62262100Y12700985D01*
X62552280Y11242150D01*
X62552280Y9754730D01*
X62262100Y8295895D01*
X61753425Y7067847D01*
X61692889Y6921700D01*
X61068758Y5987621D01*
X60866523Y5684955D01*
X59814765Y4633197D01*
X59814762Y4633195D01*
X58578020Y3806831D01*
X58578019Y3806830D01*
X58578018Y3806830D01*
X57203825Y3237620D01*
X55744990Y2947440D01*
X54257570Y2947440D01*
X52798735Y3237620D01*
X51424542Y3806830D01*
X51424541Y3806830D01*
X51424540Y3806831D01*
X50187798Y4633195D01*
X50187795Y4633197D01*
X49136037Y5684955D01*
X48933802Y5987621D01*
X48309671Y6921700D01*
X48249135Y7067847D01*
X47740460Y8295895D01*
X47450280Y9754730D01*
X47450280Y11242150D01*
X47740460Y12700985D01*
X48309670Y14075178D01*
X48570034Y14464840D01*
X49136035Y15311922D01*
X49136037Y15311925D01*
X50187795Y16363683D01*
X50215351Y16382095D01*
X51424540Y17190049D01*
X51424542Y17190050D01*
X52798735Y17759260D01*
X54257570Y18049440D01*
X55744990Y18049440D01*
X57203825Y17759260D01*
X57203825Y17759260D01*
G37*
G36*
X6499532Y8838022D02*
X6499534Y8838021D01*
X6499535Y8838021D01*
X6872793Y8683413D01*
X6872794Y8683412D01*
X7208719Y8458954D01*
X7494394Y8173279D01*
X7494396Y8173276D01*
X7718853Y7837353D01*
X7873461Y7464095D01*
X7952280Y7067846D01*
X7952280Y6663834D01*
X7873461Y6267585D01*
X7718853Y5894327D01*
X7718852Y5894326D01*
X7494394Y5558401D01*
X7208719Y5272726D01*
X7208716Y5272724D01*
X6872793Y5048267D01*
X6499535Y4893659D01*
X6499534Y4893659D01*
X6499532Y4893658D01*
X6103287Y4814840D01*
X5699273Y4814840D01*
X5303028Y4893658D01*
X5303026Y4893659D01*
X5303025Y4893659D01*
X4929767Y5048267D01*
X4593844Y5272724D01*
X4593841Y5272726D01*
X4308166Y5558401D01*
X4083708Y5894326D01*
X4083707Y5894327D01*
X3929099Y6267585D01*
X3850280Y6663834D01*
X3850280Y7067846D01*
X3929099Y7464095D01*
X4083707Y7837353D01*
X4308164Y8173276D01*
X4308166Y8173279D01*
X4593841Y8458954D01*
X4929766Y8683412D01*
X4929767Y8683413D01*
X5303025Y8838021D01*
X5303026Y8838021D01*
X5303028Y8838022D01*
X5699273Y8916840D01*
X6103287Y8916840D01*
X6499532Y8838022D01*
X6499532Y8838022D01*
G37*
G36*
X30699532Y8838022D02*
X30699534Y8838021D01*
X30699535Y8838021D01*
X31072793Y8683413D01*
X31072794Y8683412D01*
X31408719Y8458954D01*
X31694394Y8173279D01*
X31694396Y8173276D01*
X31918853Y7837353D01*
X32073461Y7464095D01*
X32152280Y7067846D01*
X32152280Y6663834D01*
X32073461Y6267585D01*
X31918853Y5894327D01*
X31918852Y5894326D01*
X31694394Y5558401D01*
X31408719Y5272726D01*
X31408716Y5272724D01*
X31072793Y5048267D01*
X30699535Y4893659D01*
X30699534Y4893659D01*
X30699532Y4893658D01*
X30303287Y4814840D01*
X29899273Y4814840D01*
X29503028Y4893658D01*
X29503026Y4893659D01*
X29503025Y4893659D01*
X29129767Y5048267D01*
X28793844Y5272724D01*
X28793841Y5272726D01*
X28508166Y5558401D01*
X28283708Y5894326D01*
X28283707Y5894327D01*
X28129099Y6267585D01*
X28050280Y6663834D01*
X28050280Y7067846D01*
X28129099Y7464095D01*
X28283707Y7837353D01*
X28508164Y8173276D01*
X28508166Y8173279D01*
X28793841Y8458954D01*
X29129766Y8683412D01*
X29129767Y8683413D01*
X29503025Y8838021D01*
X29503026Y8838021D01*
X29503028Y8838022D01*
X29899273Y8916840D01*
X30303287Y8916840D01*
X30699532Y8838022D01*
X30699532Y8838022D01*
G37*
G36*
X117203825Y20509260D02*
X118578018Y19940050D01*
X118578020Y19940049D01*
X119107361Y19586355D01*
X119814765Y19113683D01*
X120866523Y18061925D01*
X120866525Y18061922D01*
X121630354Y16918771D01*
X121692890Y16825178D01*
X122262100Y15450985D01*
X122552280Y13992150D01*
X122552280Y12504730D01*
X122262100Y11045895D01*
X121959285Y10314836D01*
X121692889Y9671700D01*
X120882560Y8458956D01*
X120866523Y8434955D01*
X119814765Y7383197D01*
X119814762Y7383195D01*
X118578020Y6556831D01*
X118578019Y6556830D01*
X118578018Y6556830D01*
X117203825Y5987620D01*
X115744990Y5697440D01*
X114257570Y5697440D01*
X112798735Y5987620D01*
X111424542Y6556830D01*
X111424541Y6556830D01*
X111424540Y6556831D01*
X110187798Y7383195D01*
X110187795Y7383197D01*
X109136037Y8434955D01*
X109120000Y8458956D01*
X108309671Y9671700D01*
X108043275Y10314836D01*
X107740460Y11045895D01*
X107450280Y12504730D01*
X107450280Y13992150D01*
X107740460Y15450985D01*
X108309670Y16825178D01*
X108372207Y16918771D01*
X109136035Y18061922D01*
X109136037Y18061925D01*
X110187795Y19113683D01*
X110895199Y19586355D01*
X111424540Y19940049D01*
X111424542Y19940050D01*
X112798735Y20509260D01*
X114257570Y20799440D01*
X115744990Y20799440D01*
X117203825Y20509260D01*
X117203825Y20509260D01*
G37*
G36*
X10480765Y12816844D02*
X10480767Y12816843D01*
X10480768Y12816843D01*
X10717535Y12718771D01*
X10930622Y12576391D01*
X11111831Y12395182D01*
X11254211Y12182095D01*
X11352284Y11945325D01*
X11402280Y11693979D01*
X11402280Y11437701D01*
X11352284Y11186355D01*
X11254211Y10949585D01*
X11111831Y10736498D01*
X10930622Y10555289D01*
X10930619Y10555287D01*
X10717535Y10412909D01*
X10480768Y10314837D01*
X10480767Y10314837D01*
X10480765Y10314836D01*
X10229419Y10264840D01*
X9973141Y10264840D01*
X9721795Y10314836D01*
X9721793Y10314837D01*
X9721792Y10314837D01*
X9485025Y10412909D01*
X9271941Y10555287D01*
X9271938Y10555289D01*
X9090729Y10736498D01*
X8948349Y10949585D01*
X8850276Y11186355D01*
X8800280Y11437701D01*
X8800280Y11693979D01*
X8850276Y11945325D01*
X8948349Y12182095D01*
X9090729Y12395182D01*
X9271938Y12576391D01*
X9485025Y12718771D01*
X9721792Y12816843D01*
X9721793Y12816843D01*
X9721795Y12816844D01*
X9973141Y12866840D01*
X10229419Y12866840D01*
X10480765Y12816844D01*
X10480765Y12816844D01*
G37*
G36*
X6280765Y12816844D02*
X6280767Y12816843D01*
X6280768Y12816843D01*
X6517535Y12718771D01*
X6730622Y12576391D01*
X6911831Y12395182D01*
X7054211Y12182095D01*
X7152284Y11945325D01*
X7202280Y11693979D01*
X7202280Y11437701D01*
X7152284Y11186355D01*
X7054211Y10949585D01*
X6911831Y10736498D01*
X6730622Y10555289D01*
X6730619Y10555287D01*
X6517535Y10412909D01*
X6280768Y10314837D01*
X6280767Y10314837D01*
X6280765Y10314836D01*
X6029419Y10264840D01*
X5773141Y10264840D01*
X5521795Y10314836D01*
X5521793Y10314837D01*
X5521792Y10314837D01*
X5285025Y10412909D01*
X5071941Y10555287D01*
X5071938Y10555289D01*
X4890729Y10736498D01*
X4748349Y10949585D01*
X4650276Y11186355D01*
X4600280Y11437701D01*
X4600280Y11693979D01*
X4650276Y11945325D01*
X4748349Y12182095D01*
X4890729Y12395182D01*
X5071938Y12576391D01*
X5285025Y12718771D01*
X5521792Y12816843D01*
X5521793Y12816843D01*
X5521795Y12816844D01*
X5773141Y12866840D01*
X6029419Y12866840D01*
X6280765Y12816844D01*
X6280765Y12816844D01*
G37*
G36*
X30480765Y12816844D02*
X30480767Y12816843D01*
X30480768Y12816843D01*
X30717535Y12718771D01*
X30930622Y12576391D01*
X31111831Y12395182D01*
X31254211Y12182095D01*
X31352284Y11945325D01*
X31402280Y11693979D01*
X31402280Y11437701D01*
X31352284Y11186355D01*
X31254211Y10949585D01*
X31111831Y10736498D01*
X30930622Y10555289D01*
X30930619Y10555287D01*
X30717535Y10412909D01*
X30480768Y10314837D01*
X30480767Y10314837D01*
X30480765Y10314836D01*
X30229419Y10264840D01*
X29973141Y10264840D01*
X29721795Y10314836D01*
X29721793Y10314837D01*
X29721792Y10314837D01*
X29485025Y10412909D01*
X29271941Y10555287D01*
X29271938Y10555289D01*
X29090729Y10736498D01*
X28948349Y10949585D01*
X28850276Y11186355D01*
X28800280Y11437701D01*
X28800280Y11693979D01*
X28850276Y11945325D01*
X28948349Y12182095D01*
X29090729Y12395182D01*
X29271938Y12576391D01*
X29485025Y12718771D01*
X29721792Y12816843D01*
X29721793Y12816843D01*
X29721795Y12816844D01*
X29973141Y12866840D01*
X30229419Y12866840D01*
X30480765Y12816844D01*
X30480765Y12816844D01*
G37*
G36*
X26280765Y12816844D02*
X26280767Y12816843D01*
X26280768Y12816843D01*
X26517535Y12718771D01*
X26730622Y12576391D01*
X26911831Y12395182D01*
X27054211Y12182095D01*
X27152284Y11945325D01*
X27202280Y11693979D01*
X27202280Y11437701D01*
X27152284Y11186355D01*
X27054211Y10949585D01*
X26911831Y10736498D01*
X26730622Y10555289D01*
X26730619Y10555287D01*
X26517535Y10412909D01*
X26280768Y10314837D01*
X26280767Y10314837D01*
X26280765Y10314836D01*
X26029419Y10264840D01*
X25773141Y10264840D01*
X25521795Y10314836D01*
X25521793Y10314837D01*
X25521792Y10314837D01*
X25285025Y10412909D01*
X25071941Y10555287D01*
X25071938Y10555289D01*
X24890729Y10736498D01*
X24748349Y10949585D01*
X24650276Y11186355D01*
X24600280Y11437701D01*
X24600280Y11693979D01*
X24650276Y11945325D01*
X24748349Y12182095D01*
X24890729Y12395182D01*
X25071938Y12576391D01*
X25285025Y12718771D01*
X25521792Y12816843D01*
X25521793Y12816843D01*
X25521795Y12816844D01*
X25773141Y12866840D01*
X26029419Y12866840D01*
X26280765Y12816844D01*
X26280765Y12816844D01*
G37*
G36*
X26280765Y17016844D02*
X26280767Y17016843D01*
X26280768Y17016843D01*
X26517535Y16918771D01*
X26730622Y16776391D01*
X26911831Y16595182D01*
X27054211Y16382095D01*
X27152284Y16145325D01*
X27202280Y15893979D01*
X27202280Y15637701D01*
X27152284Y15386355D01*
X27054211Y15149585D01*
X26911831Y14936498D01*
X26730622Y14755289D01*
X26730619Y14755287D01*
X26517535Y14612909D01*
X26280768Y14514837D01*
X26280767Y14514837D01*
X26280765Y14514836D01*
X26029419Y14464840D01*
X25773141Y14464840D01*
X25521795Y14514836D01*
X25521793Y14514837D01*
X25521792Y14514837D01*
X25285025Y14612909D01*
X25071941Y14755287D01*
X25071938Y14755289D01*
X24890729Y14936498D01*
X24748349Y15149585D01*
X24650276Y15386355D01*
X24600280Y15637701D01*
X24600280Y15893979D01*
X24650276Y16145325D01*
X24748349Y16382095D01*
X24890729Y16595182D01*
X25071938Y16776391D01*
X25285025Y16918771D01*
X25521792Y17016843D01*
X25521793Y17016843D01*
X25521795Y17016844D01*
X25773141Y17066840D01*
X26029419Y17066840D01*
X26280765Y17016844D01*
X26280765Y17016844D01*
G37*
G36*
X10480765Y17016844D02*
X10480767Y17016843D01*
X10480768Y17016843D01*
X10717535Y16918771D01*
X10930622Y16776391D01*
X11111831Y16595182D01*
X11254211Y16382095D01*
X11352284Y16145325D01*
X11402280Y15893979D01*
X11402280Y15637701D01*
X11352284Y15386355D01*
X11254211Y15149585D01*
X11111831Y14936498D01*
X10930622Y14755289D01*
X10930619Y14755287D01*
X10717535Y14612909D01*
X10480768Y14514837D01*
X10480767Y14514837D01*
X10480765Y14514836D01*
X10229419Y14464840D01*
X9973141Y14464840D01*
X9721795Y14514836D01*
X9721793Y14514837D01*
X9721792Y14514837D01*
X9485025Y14612909D01*
X9271941Y14755287D01*
X9271938Y14755289D01*
X9090729Y14936498D01*
X8948349Y15149585D01*
X8850276Y15386355D01*
X8800280Y15637701D01*
X8800280Y15893979D01*
X8850276Y16145325D01*
X8948349Y16382095D01*
X9090729Y16595182D01*
X9271938Y16776391D01*
X9485025Y16918771D01*
X9721792Y17016843D01*
X9721793Y17016843D01*
X9721795Y17016844D01*
X9973141Y17066840D01*
X10229419Y17066840D01*
X10480765Y17016844D01*
X10480765Y17016844D01*
G37*
G36*
X6280765Y17016844D02*
X6280767Y17016843D01*
X6280768Y17016843D01*
X6517535Y16918771D01*
X6730622Y16776391D01*
X6911831Y16595182D01*
X7054211Y16382095D01*
X7152284Y16145325D01*
X7202280Y15893979D01*
X7202280Y15637701D01*
X7152284Y15386355D01*
X7054211Y15149585D01*
X6911831Y14936498D01*
X6730622Y14755289D01*
X6730619Y14755287D01*
X6517535Y14612909D01*
X6280768Y14514837D01*
X6280767Y14514837D01*
X6280765Y14514836D01*
X6029419Y14464840D01*
X5773141Y14464840D01*
X5521795Y14514836D01*
X5521793Y14514837D01*
X5521792Y14514837D01*
X5285025Y14612909D01*
X5071941Y14755287D01*
X5071938Y14755289D01*
X4890729Y14936498D01*
X4748349Y15149585D01*
X4650276Y15386355D01*
X4600280Y15637701D01*
X4600280Y15893979D01*
X4650276Y16145325D01*
X4748349Y16382095D01*
X4890729Y16595182D01*
X5071938Y16776391D01*
X5285025Y16918771D01*
X5521792Y17016843D01*
X5521793Y17016843D01*
X5521795Y17016844D01*
X5773141Y17066840D01*
X6029419Y17066840D01*
X6280765Y17016844D01*
X6280765Y17016844D01*
G37*
G36*
X30480765Y17016844D02*
X30480767Y17016843D01*
X30480768Y17016843D01*
X30717535Y16918771D01*
X30930622Y16776391D01*
X31111831Y16595182D01*
X31254211Y16382095D01*
X31352284Y16145325D01*
X31402280Y15893979D01*
X31402280Y15637701D01*
X31352284Y15386355D01*
X31254211Y15149585D01*
X31111831Y14936498D01*
X30930622Y14755289D01*
X30930619Y14755287D01*
X30717535Y14612909D01*
X30480768Y14514837D01*
X30480767Y14514837D01*
X30480765Y14514836D01*
X30229419Y14464840D01*
X29973141Y14464840D01*
X29721795Y14514836D01*
X29721793Y14514837D01*
X29721792Y14514837D01*
X29485025Y14612909D01*
X29271941Y14755287D01*
X29271938Y14755289D01*
X29090729Y14936498D01*
X28948349Y15149585D01*
X28850276Y15386355D01*
X28800280Y15637701D01*
X28800280Y15893979D01*
X28850276Y16145325D01*
X28948349Y16382095D01*
X29090729Y16595182D01*
X29271938Y16776391D01*
X29485025Y16918771D01*
X29721792Y17016843D01*
X29721793Y17016843D01*
X29721795Y17016844D01*
X29973141Y17066840D01*
X30229419Y17066840D01*
X30480765Y17016844D01*
X30480765Y17016844D01*
G37*
G36*
X26280765Y21216844D02*
X26280767Y21216843D01*
X26280768Y21216843D01*
X26517535Y21118771D01*
X26730622Y20976391D01*
X26911831Y20795182D01*
X27054211Y20582095D01*
X27152284Y20345325D01*
X27202280Y20093979D01*
X27202280Y19837701D01*
X27152284Y19586355D01*
X27054211Y19349585D01*
X26911831Y19136498D01*
X26730622Y18955289D01*
X26730619Y18955287D01*
X26517535Y18812909D01*
X26280768Y18714837D01*
X26280767Y18714837D01*
X26280765Y18714836D01*
X26029419Y18664840D01*
X25773141Y18664840D01*
X25521795Y18714836D01*
X25521793Y18714837D01*
X25521792Y18714837D01*
X25285025Y18812909D01*
X25071941Y18955287D01*
X25071938Y18955289D01*
X24890729Y19136498D01*
X24748349Y19349585D01*
X24650276Y19586355D01*
X24600280Y19837701D01*
X24600280Y20093979D01*
X24650276Y20345325D01*
X24748349Y20582095D01*
X24890729Y20795182D01*
X25071938Y20976391D01*
X25285025Y21118771D01*
X25521792Y21216843D01*
X25521793Y21216843D01*
X25521795Y21216844D01*
X25773141Y21266840D01*
X26029419Y21266840D01*
X26280765Y21216844D01*
X26280765Y21216844D01*
G37*
G36*
X6280765Y21216844D02*
X6280767Y21216843D01*
X6280768Y21216843D01*
X6517535Y21118771D01*
X6730622Y20976391D01*
X6911831Y20795182D01*
X7054211Y20582095D01*
X7152284Y20345325D01*
X7202280Y20093979D01*
X7202280Y19837701D01*
X7152284Y19586355D01*
X7054211Y19349585D01*
X6911831Y19136498D01*
X6730622Y18955289D01*
X6730619Y18955287D01*
X6517535Y18812909D01*
X6280768Y18714837D01*
X6280767Y18714837D01*
X6280765Y18714836D01*
X6029419Y18664840D01*
X5773141Y18664840D01*
X5521795Y18714836D01*
X5521793Y18714837D01*
X5521792Y18714837D01*
X5285025Y18812909D01*
X5071941Y18955287D01*
X5071938Y18955289D01*
X4890729Y19136498D01*
X4748349Y19349585D01*
X4650276Y19586355D01*
X4600280Y19837701D01*
X4600280Y20093979D01*
X4650276Y20345325D01*
X4748349Y20582095D01*
X4890729Y20795182D01*
X5071938Y20976391D01*
X5285025Y21118771D01*
X5521792Y21216843D01*
X5521793Y21216843D01*
X5521795Y21216844D01*
X5773141Y21266840D01*
X6029419Y21266840D01*
X6280765Y21216844D01*
X6280765Y21216844D01*
G37*
G36*
X10480765Y21216844D02*
X10480767Y21216843D01*
X10480768Y21216843D01*
X10717535Y21118771D01*
X10930622Y20976391D01*
X11111831Y20795182D01*
X11254211Y20582095D01*
X11352284Y20345325D01*
X11402280Y20093979D01*
X11402280Y19837701D01*
X11352284Y19586355D01*
X11254211Y19349585D01*
X11111831Y19136498D01*
X10930622Y18955289D01*
X10930619Y18955287D01*
X10717535Y18812909D01*
X10480768Y18714837D01*
X10480767Y18714837D01*
X10480765Y18714836D01*
X10229419Y18664840D01*
X9973141Y18664840D01*
X9721795Y18714836D01*
X9721793Y18714837D01*
X9721792Y18714837D01*
X9485025Y18812909D01*
X9271941Y18955287D01*
X9271938Y18955289D01*
X9090729Y19136498D01*
X8948349Y19349585D01*
X8850276Y19586355D01*
X8800280Y19837701D01*
X8800280Y20093979D01*
X8850276Y20345325D01*
X8948349Y20582095D01*
X9090729Y20795182D01*
X9271938Y20976391D01*
X9485025Y21118771D01*
X9721792Y21216843D01*
X9721793Y21216843D01*
X9721795Y21216844D01*
X9973141Y21266840D01*
X10229419Y21266840D01*
X10480765Y21216844D01*
X10480765Y21216844D01*
G37*
G36*
X30480765Y21216844D02*
X30480767Y21216843D01*
X30480768Y21216843D01*
X30717535Y21118771D01*
X30930622Y20976391D01*
X31111831Y20795182D01*
X31254211Y20582095D01*
X31352284Y20345325D01*
X31402280Y20093979D01*
X31402280Y19837701D01*
X31352284Y19586355D01*
X31254211Y19349585D01*
X31111831Y19136498D01*
X30930622Y18955289D01*
X30930619Y18955287D01*
X30717535Y18812909D01*
X30480768Y18714837D01*
X30480767Y18714837D01*
X30480765Y18714836D01*
X30229419Y18664840D01*
X29973141Y18664840D01*
X29721795Y18714836D01*
X29721793Y18714837D01*
X29721792Y18714837D01*
X29485025Y18812909D01*
X29271941Y18955287D01*
X29271938Y18955289D01*
X29090729Y19136498D01*
X28948349Y19349585D01*
X28850276Y19586355D01*
X28800280Y19837701D01*
X28800280Y20093979D01*
X28850276Y20345325D01*
X28948349Y20582095D01*
X29090729Y20795182D01*
X29271938Y20976391D01*
X29485025Y21118771D01*
X29721792Y21216843D01*
X29721793Y21216843D01*
X29721795Y21216844D01*
X29973141Y21266840D01*
X30229419Y21266840D01*
X30480765Y21216844D01*
X30480765Y21216844D01*
G37*
G36*
X30699532Y26638022D02*
X30699534Y26638021D01*
X30699535Y26638021D01*
X31072793Y26483413D01*
X31072794Y26483412D01*
X31408719Y26258954D01*
X31694394Y25973279D01*
X31694396Y25973276D01*
X31918853Y25637353D01*
X32073461Y25264095D01*
X32152280Y24867846D01*
X32152280Y24463834D01*
X32073461Y24067585D01*
X31918853Y23694327D01*
X31918852Y23694326D01*
X31694394Y23358401D01*
X31408719Y23072726D01*
X31408716Y23072724D01*
X31072793Y22848267D01*
X30699535Y22693659D01*
X30699534Y22693659D01*
X30699532Y22693658D01*
X30303287Y22614840D01*
X29899273Y22614840D01*
X29503028Y22693658D01*
X29503026Y22693659D01*
X29503025Y22693659D01*
X29129767Y22848267D01*
X28793844Y23072724D01*
X28793841Y23072726D01*
X28508166Y23358401D01*
X28283708Y23694326D01*
X28283707Y23694327D01*
X28129099Y24067585D01*
X28050280Y24463834D01*
X28050280Y24867846D01*
X28129099Y25264095D01*
X28283707Y25637353D01*
X28508164Y25973276D01*
X28508166Y25973279D01*
X28793841Y26258954D01*
X29129766Y26483412D01*
X29129767Y26483413D01*
X29503025Y26638021D01*
X29503026Y26638021D01*
X29503028Y26638022D01*
X29899273Y26716840D01*
X30303287Y26716840D01*
X30699532Y26638022D01*
X30699532Y26638022D01*
G37*
G36*
X6499532Y26638022D02*
X6499534Y26638021D01*
X6499535Y26638021D01*
X6872793Y26483413D01*
X6872794Y26483412D01*
X7208719Y26258954D01*
X7494394Y25973279D01*
X7494396Y25973276D01*
X7718853Y25637353D01*
X7873461Y25264095D01*
X7952280Y24867846D01*
X7952280Y24463834D01*
X7873461Y24067585D01*
X7718853Y23694327D01*
X7718852Y23694326D01*
X7494394Y23358401D01*
X7208719Y23072726D01*
X7208716Y23072724D01*
X6872793Y22848267D01*
X6499535Y22693659D01*
X6499534Y22693659D01*
X6499532Y22693658D01*
X6103287Y22614840D01*
X5699273Y22614840D01*
X5303028Y22693658D01*
X5303026Y22693659D01*
X5303025Y22693659D01*
X4929767Y22848267D01*
X4593844Y23072724D01*
X4593841Y23072726D01*
X4308166Y23358401D01*
X4083708Y23694326D01*
X4083707Y23694327D01*
X3929099Y24067585D01*
X3850280Y24463834D01*
X3850280Y24867846D01*
X3929099Y25264095D01*
X4083707Y25637353D01*
X4308164Y25973276D01*
X4308166Y25973279D01*
X4593841Y26258954D01*
X4929766Y26483412D01*
X4929767Y26483413D01*
X5303025Y26638021D01*
X5303026Y26638021D01*
X5303028Y26638022D01*
X5699273Y26716840D01*
X6103287Y26716840D01*
X6499532Y26638022D01*
X6499532Y26638022D01*
G37*
G36*
X57203825Y40259260D02*
X58578018Y39690050D01*
X58578020Y39690049D01*
X59390097Y39147437D01*
X59814765Y38863683D01*
X60866523Y37811925D01*
X60866525Y37811922D01*
X61629564Y36669953D01*
X61692890Y36575178D01*
X62262100Y35200985D01*
X62552280Y33742150D01*
X62552280Y32254730D01*
X62262100Y30795895D01*
X61692890Y29421702D01*
X61692889Y29421700D01*
X61449091Y29056830D01*
X60866523Y28184955D01*
X59814765Y27133197D01*
X59814762Y27133195D01*
X58578020Y26306831D01*
X58578019Y26306830D01*
X58578018Y26306830D01*
X57203825Y25737620D01*
X55744990Y25447440D01*
X54257570Y25447440D01*
X52798735Y25737620D01*
X51424542Y26306830D01*
X51424541Y26306830D01*
X51424540Y26306831D01*
X50187798Y27133195D01*
X50187795Y27133197D01*
X49136037Y28184955D01*
X48553469Y29056830D01*
X48309671Y29421700D01*
X48309670Y29421702D01*
X47740460Y30795895D01*
X47450280Y32254730D01*
X47450280Y33742150D01*
X47740460Y35200985D01*
X48309670Y36575178D01*
X48372997Y36669953D01*
X49136035Y37811922D01*
X49136037Y37811925D01*
X50187795Y38863683D01*
X50612463Y39147437D01*
X51424540Y39690049D01*
X51424542Y39690050D01*
X52798735Y40259260D01*
X54257570Y40549440D01*
X55744990Y40549440D01*
X57203825Y40259260D01*
X57203825Y40259260D01*
G37*
G36*
X117203825Y43009260D02*
X118578018Y42440050D01*
X118578020Y42440049D01*
X119686420Y41699440D01*
X119814765Y41613683D01*
X120866523Y40561925D01*
X120866525Y40561922D01*
X121650990Y39387887D01*
X121692890Y39325178D01*
X122262100Y37950985D01*
X122552280Y36492150D01*
X122552280Y35004730D01*
X122262100Y33545895D01*
X121692890Y32171702D01*
X120866523Y30934955D01*
X119814765Y29883197D01*
X119814762Y29883195D01*
X118578020Y29056831D01*
X118578019Y29056830D01*
X118578018Y29056830D01*
X117203825Y28487620D01*
X115744990Y28197440D01*
X114257570Y28197440D01*
X112798735Y28487620D01*
X111424542Y29056830D01*
X111424541Y29056830D01*
X111424540Y29056831D01*
X110187798Y29883195D01*
X110187795Y29883197D01*
X109136037Y30934955D01*
X108309670Y32171702D01*
X107740460Y33545895D01*
X107450280Y35004730D01*
X107450280Y36492150D01*
X107740460Y37950985D01*
X108309670Y39325178D01*
X108351571Y39387887D01*
X109136035Y40561922D01*
X109136037Y40561925D01*
X110187795Y41613683D01*
X110316140Y41699440D01*
X111424540Y42440049D01*
X111424542Y42440050D01*
X112798735Y43009260D01*
X114257570Y43299440D01*
X115744990Y43299440D01*
X117203825Y43009260D01*
X117203825Y43009260D01*
G37*
G36*
X30699532Y37670622D02*
X30699534Y37670621D01*
X30699535Y37670621D01*
X31072793Y37516013D01*
X31072794Y37516012D01*
X31408719Y37291554D01*
X31694394Y37005879D01*
X31694396Y37005876D01*
X31918853Y36669953D01*
X32073461Y36296695D01*
X32073462Y36296692D01*
X32152280Y35900447D01*
X32152280Y35496433D01*
X32093512Y35200985D01*
X32073461Y35100185D01*
X31918853Y34726927D01*
X31918852Y34726926D01*
X31694394Y34391001D01*
X31408719Y34105326D01*
X31408716Y34105324D01*
X31072793Y33880867D01*
X30699535Y33726259D01*
X30699534Y33726259D01*
X30699532Y33726258D01*
X30303287Y33647440D01*
X29899273Y33647440D01*
X29503028Y33726258D01*
X29503026Y33726259D01*
X29503025Y33726259D01*
X29129767Y33880867D01*
X28793844Y34105324D01*
X28793841Y34105326D01*
X28508166Y34391001D01*
X28283708Y34726926D01*
X28283707Y34726927D01*
X28129099Y35100185D01*
X28109049Y35200985D01*
X28050280Y35496433D01*
X28050280Y35900447D01*
X28129098Y36296692D01*
X28129099Y36296695D01*
X28283707Y36669953D01*
X28508164Y37005876D01*
X28508166Y37005879D01*
X28793841Y37291554D01*
X29129766Y37516012D01*
X29129767Y37516013D01*
X29503025Y37670621D01*
X29503026Y37670621D01*
X29503028Y37670622D01*
X29899273Y37749440D01*
X30303287Y37749440D01*
X30699532Y37670622D01*
X30699532Y37670622D01*
G37*
G36*
X6499532Y37670622D02*
X6499534Y37670621D01*
X6499535Y37670621D01*
X6872793Y37516013D01*
X6872794Y37516012D01*
X7208719Y37291554D01*
X7494394Y37005879D01*
X7494396Y37005876D01*
X7718853Y36669953D01*
X7873461Y36296695D01*
X7873462Y36296692D01*
X7952280Y35900447D01*
X7952280Y35496433D01*
X7893512Y35200985D01*
X7873461Y35100185D01*
X7718853Y34726927D01*
X7718852Y34726926D01*
X7494394Y34391001D01*
X7208719Y34105326D01*
X7208716Y34105324D01*
X6872793Y33880867D01*
X6499535Y33726259D01*
X6499534Y33726259D01*
X6499532Y33726258D01*
X6103287Y33647440D01*
X5699273Y33647440D01*
X5303028Y33726258D01*
X5303026Y33726259D01*
X5303025Y33726259D01*
X4929767Y33880867D01*
X4593844Y34105324D01*
X4593841Y34105326D01*
X4308166Y34391001D01*
X4083708Y34726926D01*
X4083707Y34726927D01*
X3929099Y35100185D01*
X3909049Y35200985D01*
X3850280Y35496433D01*
X3850280Y35900447D01*
X3929098Y36296692D01*
X3929099Y36296695D01*
X4083707Y36669953D01*
X4308164Y37005876D01*
X4308166Y37005879D01*
X4593841Y37291554D01*
X4929766Y37516012D01*
X4929767Y37516013D01*
X5303025Y37670621D01*
X5303026Y37670621D01*
X5303028Y37670622D01*
X5699273Y37749440D01*
X6103287Y37749440D01*
X6499532Y37670622D01*
X6499532Y37670622D01*
G37*
G36*
X10480765Y41649444D02*
X10480767Y41649443D01*
X10480768Y41649443D01*
X10567100Y41613683D01*
X10717535Y41551371D01*
X10930622Y41408991D01*
X11111831Y41227782D01*
X11254211Y41014695D01*
X11352284Y40777925D01*
X11402280Y40526579D01*
X11402280Y40270301D01*
X11352284Y40018955D01*
X11254211Y39782185D01*
X11111831Y39569098D01*
X10930622Y39387889D01*
X10930619Y39387887D01*
X10717535Y39245509D01*
X10480768Y39147437D01*
X10480767Y39147437D01*
X10480765Y39147436D01*
X10229419Y39097440D01*
X9973141Y39097440D01*
X9721795Y39147436D01*
X9721793Y39147437D01*
X9721792Y39147437D01*
X9485025Y39245509D01*
X9271941Y39387887D01*
X9271938Y39387889D01*
X9090729Y39569098D01*
X8948349Y39782185D01*
X8850276Y40018955D01*
X8800280Y40270301D01*
X8800280Y40526579D01*
X8850276Y40777925D01*
X8948349Y41014695D01*
X9090729Y41227782D01*
X9271938Y41408991D01*
X9485025Y41551371D01*
X9635460Y41613683D01*
X9721792Y41649443D01*
X9721793Y41649443D01*
X9721795Y41649444D01*
X9973141Y41699440D01*
X10229419Y41699440D01*
X10480765Y41649444D01*
X10480765Y41649444D01*
G37*
G36*
X6280765Y41649444D02*
X6280767Y41649443D01*
X6280768Y41649443D01*
X6367100Y41613683D01*
X6517535Y41551371D01*
X6730622Y41408991D01*
X6911831Y41227782D01*
X7054211Y41014695D01*
X7152284Y40777925D01*
X7202280Y40526579D01*
X7202280Y40270301D01*
X7152284Y40018955D01*
X7054211Y39782185D01*
X6911831Y39569098D01*
X6730622Y39387889D01*
X6730619Y39387887D01*
X6517535Y39245509D01*
X6280768Y39147437D01*
X6280767Y39147437D01*
X6280765Y39147436D01*
X6029419Y39097440D01*
X5773141Y39097440D01*
X5521795Y39147436D01*
X5521793Y39147437D01*
X5521792Y39147437D01*
X5285025Y39245509D01*
X5071941Y39387887D01*
X5071938Y39387889D01*
X4890729Y39569098D01*
X4748349Y39782185D01*
X4650276Y40018955D01*
X4600280Y40270301D01*
X4600280Y40526579D01*
X4650276Y40777925D01*
X4748349Y41014695D01*
X4890729Y41227782D01*
X5071938Y41408991D01*
X5285025Y41551371D01*
X5435460Y41613683D01*
X5521792Y41649443D01*
X5521793Y41649443D01*
X5521795Y41649444D01*
X5773141Y41699440D01*
X6029419Y41699440D01*
X6280765Y41649444D01*
X6280765Y41649444D01*
G37*
G36*
X30480765Y41649444D02*
X30480767Y41649443D01*
X30480768Y41649443D01*
X30567100Y41613683D01*
X30717535Y41551371D01*
X30930622Y41408991D01*
X31111831Y41227782D01*
X31254211Y41014695D01*
X31352284Y40777925D01*
X31402280Y40526579D01*
X31402280Y40270301D01*
X31352284Y40018955D01*
X31254211Y39782185D01*
X31111831Y39569098D01*
X30930622Y39387889D01*
X30930619Y39387887D01*
X30717535Y39245509D01*
X30480768Y39147437D01*
X30480767Y39147437D01*
X30480765Y39147436D01*
X30229419Y39097440D01*
X29973141Y39097440D01*
X29721795Y39147436D01*
X29721793Y39147437D01*
X29721792Y39147437D01*
X29485025Y39245509D01*
X29271941Y39387887D01*
X29271938Y39387889D01*
X29090729Y39569098D01*
X28948349Y39782185D01*
X28850276Y40018955D01*
X28800280Y40270301D01*
X28800280Y40526579D01*
X28850276Y40777925D01*
X28948349Y41014695D01*
X29090729Y41227782D01*
X29271938Y41408991D01*
X29485025Y41551371D01*
X29635460Y41613683D01*
X29721792Y41649443D01*
X29721793Y41649443D01*
X29721795Y41649444D01*
X29973141Y41699440D01*
X30229419Y41699440D01*
X30480765Y41649444D01*
X30480765Y41649444D01*
G37*
G36*
X26280765Y41649444D02*
X26280767Y41649443D01*
X26280768Y41649443D01*
X26367100Y41613683D01*
X26517535Y41551371D01*
X26730622Y41408991D01*
X26911831Y41227782D01*
X27054211Y41014695D01*
X27152284Y40777925D01*
X27202280Y40526579D01*
X27202280Y40270301D01*
X27152284Y40018955D01*
X27054211Y39782185D01*
X26911831Y39569098D01*
X26730622Y39387889D01*
X26730619Y39387887D01*
X26517535Y39245509D01*
X26280768Y39147437D01*
X26280767Y39147437D01*
X26280765Y39147436D01*
X26029419Y39097440D01*
X25773141Y39097440D01*
X25521795Y39147436D01*
X25521793Y39147437D01*
X25521792Y39147437D01*
X25285025Y39245509D01*
X25071941Y39387887D01*
X25071938Y39387889D01*
X24890729Y39569098D01*
X24748349Y39782185D01*
X24650276Y40018955D01*
X24600280Y40270301D01*
X24600280Y40526579D01*
X24650276Y40777925D01*
X24748349Y41014695D01*
X24890729Y41227782D01*
X25071938Y41408991D01*
X25285025Y41551371D01*
X25435460Y41613683D01*
X25521792Y41649443D01*
X25521793Y41649443D01*
X25521795Y41649444D01*
X25773141Y41699440D01*
X26029419Y41699440D01*
X26280765Y41649444D01*
X26280765Y41649444D01*
G37*
G36*
X30480765Y45849444D02*
X30480767Y45849443D01*
X30480768Y45849443D01*
X30717535Y45751371D01*
X30930622Y45608991D01*
X31111831Y45427782D01*
X31254211Y45214695D01*
X31352284Y44977925D01*
X31402280Y44726579D01*
X31402280Y44470301D01*
X31352284Y44218955D01*
X31254211Y43982185D01*
X31111831Y43769098D01*
X30930622Y43587889D01*
X30930619Y43587887D01*
X30717535Y43445509D01*
X30480768Y43347437D01*
X30480767Y43347437D01*
X30480765Y43347436D01*
X30229419Y43297440D01*
X29973141Y43297440D01*
X29721795Y43347436D01*
X29721793Y43347437D01*
X29721792Y43347437D01*
X29485025Y43445509D01*
X29271941Y43587887D01*
X29271938Y43587889D01*
X29090729Y43769098D01*
X28948349Y43982185D01*
X28850276Y44218955D01*
X28800280Y44470301D01*
X28800280Y44726579D01*
X28850276Y44977925D01*
X28948349Y45214695D01*
X29090729Y45427782D01*
X29271938Y45608991D01*
X29485025Y45751371D01*
X29721792Y45849443D01*
X29721793Y45849443D01*
X29721795Y45849444D01*
X29973141Y45899440D01*
X30229419Y45899440D01*
X30480765Y45849444D01*
X30480765Y45849444D01*
G37*
G36*
X6280765Y45849444D02*
X6280767Y45849443D01*
X6280768Y45849443D01*
X6517535Y45751371D01*
X6730622Y45608991D01*
X6911831Y45427782D01*
X7054211Y45214695D01*
X7152284Y44977925D01*
X7202280Y44726579D01*
X7202280Y44470301D01*
X7152284Y44218955D01*
X7054211Y43982185D01*
X6911831Y43769098D01*
X6730622Y43587889D01*
X6730619Y43587887D01*
X6517535Y43445509D01*
X6280768Y43347437D01*
X6280767Y43347437D01*
X6280765Y43347436D01*
X6029419Y43297440D01*
X5773141Y43297440D01*
X5521795Y43347436D01*
X5521793Y43347437D01*
X5521792Y43347437D01*
X5285025Y43445509D01*
X5071941Y43587887D01*
X5071938Y43587889D01*
X4890729Y43769098D01*
X4748349Y43982185D01*
X4650276Y44218955D01*
X4600280Y44470301D01*
X4600280Y44726579D01*
X4650276Y44977925D01*
X4748349Y45214695D01*
X4890729Y45427782D01*
X5071938Y45608991D01*
X5285025Y45751371D01*
X5521792Y45849443D01*
X5521793Y45849443D01*
X5521795Y45849444D01*
X5773141Y45899440D01*
X6029419Y45899440D01*
X6280765Y45849444D01*
X6280765Y45849444D01*
G37*
G36*
X26280765Y45849444D02*
X26280767Y45849443D01*
X26280768Y45849443D01*
X26517535Y45751371D01*
X26730622Y45608991D01*
X26911831Y45427782D01*
X27054211Y45214695D01*
X27152284Y44977925D01*
X27202280Y44726579D01*
X27202280Y44470301D01*
X27152284Y44218955D01*
X27054211Y43982185D01*
X26911831Y43769098D01*
X26730622Y43587889D01*
X26730619Y43587887D01*
X26517535Y43445509D01*
X26280768Y43347437D01*
X26280767Y43347437D01*
X26280765Y43347436D01*
X26029419Y43297440D01*
X25773141Y43297440D01*
X25521795Y43347436D01*
X25521793Y43347437D01*
X25521792Y43347437D01*
X25285025Y43445509D01*
X25071941Y43587887D01*
X25071938Y43587889D01*
X24890729Y43769098D01*
X24748349Y43982185D01*
X24650276Y44218955D01*
X24600280Y44470301D01*
X24600280Y44726579D01*
X24650276Y44977925D01*
X24748349Y45214695D01*
X24890729Y45427782D01*
X25071938Y45608991D01*
X25285025Y45751371D01*
X25521792Y45849443D01*
X25521793Y45849443D01*
X25521795Y45849444D01*
X25773141Y45899440D01*
X26029419Y45899440D01*
X26280765Y45849444D01*
X26280765Y45849444D01*
G37*
G36*
X10480765Y45849444D02*
X10480767Y45849443D01*
X10480768Y45849443D01*
X10717535Y45751371D01*
X10930622Y45608991D01*
X11111831Y45427782D01*
X11254211Y45214695D01*
X11352284Y44977925D01*
X11402280Y44726579D01*
X11402280Y44470301D01*
X11352284Y44218955D01*
X11254211Y43982185D01*
X11111831Y43769098D01*
X10930622Y43587889D01*
X10930619Y43587887D01*
X10717535Y43445509D01*
X10480768Y43347437D01*
X10480767Y43347437D01*
X10480765Y43347436D01*
X10229419Y43297440D01*
X9973141Y43297440D01*
X9721795Y43347436D01*
X9721793Y43347437D01*
X9721792Y43347437D01*
X9485025Y43445509D01*
X9271941Y43587887D01*
X9271938Y43587889D01*
X9090729Y43769098D01*
X8948349Y43982185D01*
X8850276Y44218955D01*
X8800280Y44470301D01*
X8800280Y44726579D01*
X8850276Y44977925D01*
X8948349Y45214695D01*
X9090729Y45427782D01*
X9271938Y45608991D01*
X9485025Y45751371D01*
X9721792Y45849443D01*
X9721793Y45849443D01*
X9721795Y45849444D01*
X9973141Y45899440D01*
X10229419Y45899440D01*
X10480765Y45849444D01*
X10480765Y45849444D01*
G37*
G36*
X30480765Y50049444D02*
X30480767Y50049443D01*
X30480768Y50049443D01*
X30717535Y49951371D01*
X30930622Y49808991D01*
X31111831Y49627782D01*
X31254211Y49414695D01*
X31352284Y49177925D01*
X31402280Y48926579D01*
X31402280Y48670301D01*
X31352284Y48418955D01*
X31254211Y48182185D01*
X31111831Y47969098D01*
X30930622Y47787889D01*
X30930619Y47787887D01*
X30717535Y47645509D01*
X30480768Y47547437D01*
X30480767Y47547437D01*
X30480765Y47547436D01*
X30229419Y47497440D01*
X29973141Y47497440D01*
X29721795Y47547436D01*
X29721793Y47547437D01*
X29721792Y47547437D01*
X29485025Y47645509D01*
X29271941Y47787887D01*
X29271938Y47787889D01*
X29090729Y47969098D01*
X28948349Y48182185D01*
X28850276Y48418955D01*
X28800280Y48670301D01*
X28800280Y48926579D01*
X28850276Y49177925D01*
X28948349Y49414695D01*
X29090729Y49627782D01*
X29271938Y49808991D01*
X29485025Y49951371D01*
X29721792Y50049443D01*
X29721793Y50049443D01*
X29721795Y50049444D01*
X29973141Y50099440D01*
X30229419Y50099440D01*
X30480765Y50049444D01*
X30480765Y50049444D01*
G37*
G36*
X6280765Y50049444D02*
X6280767Y50049443D01*
X6280768Y50049443D01*
X6517535Y49951371D01*
X6730622Y49808991D01*
X6911831Y49627782D01*
X7054211Y49414695D01*
X7152284Y49177925D01*
X7202280Y48926579D01*
X7202280Y48670301D01*
X7152284Y48418955D01*
X7054211Y48182185D01*
X6911831Y47969098D01*
X6730622Y47787889D01*
X6730619Y47787887D01*
X6517535Y47645509D01*
X6280768Y47547437D01*
X6280767Y47547437D01*
X6280765Y47547436D01*
X6029419Y47497440D01*
X5773141Y47497440D01*
X5521795Y47547436D01*
X5521793Y47547437D01*
X5521792Y47547437D01*
X5285025Y47645509D01*
X5071941Y47787887D01*
X5071938Y47787889D01*
X4890729Y47969098D01*
X4748349Y48182185D01*
X4650276Y48418955D01*
X4600280Y48670301D01*
X4600280Y48926579D01*
X4650276Y49177925D01*
X4748349Y49414695D01*
X4890729Y49627782D01*
X5071938Y49808991D01*
X5285025Y49951371D01*
X5521792Y50049443D01*
X5521793Y50049443D01*
X5521795Y50049444D01*
X5773141Y50099440D01*
X6029419Y50099440D01*
X6280765Y50049444D01*
X6280765Y50049444D01*
G37*
G36*
X10480765Y50049444D02*
X10480767Y50049443D01*
X10480768Y50049443D01*
X10717535Y49951371D01*
X10930622Y49808991D01*
X11111831Y49627782D01*
X11254211Y49414695D01*
X11352284Y49177925D01*
X11402280Y48926579D01*
X11402280Y48670301D01*
X11352284Y48418955D01*
X11254211Y48182185D01*
X11111831Y47969098D01*
X10930622Y47787889D01*
X10930619Y47787887D01*
X10717535Y47645509D01*
X10480768Y47547437D01*
X10480767Y47547437D01*
X10480765Y47547436D01*
X10229419Y47497440D01*
X9973141Y47497440D01*
X9721795Y47547436D01*
X9721793Y47547437D01*
X9721792Y47547437D01*
X9485025Y47645509D01*
X9271941Y47787887D01*
X9271938Y47787889D01*
X9090729Y47969098D01*
X8948349Y48182185D01*
X8850276Y48418955D01*
X8800280Y48670301D01*
X8800280Y48926579D01*
X8850276Y49177925D01*
X8948349Y49414695D01*
X9090729Y49627782D01*
X9271938Y49808991D01*
X9485025Y49951371D01*
X9721792Y50049443D01*
X9721793Y50049443D01*
X9721795Y50049444D01*
X9973141Y50099440D01*
X10229419Y50099440D01*
X10480765Y50049444D01*
X10480765Y50049444D01*
G37*
G36*
X26280765Y50049444D02*
X26280767Y50049443D01*
X26280768Y50049443D01*
X26517535Y49951371D01*
X26730622Y49808991D01*
X26911831Y49627782D01*
X27054211Y49414695D01*
X27152284Y49177925D01*
X27202280Y48926579D01*
X27202280Y48670301D01*
X27152284Y48418955D01*
X27054211Y48182185D01*
X26911831Y47969098D01*
X26730622Y47787889D01*
X26730619Y47787887D01*
X26517535Y47645509D01*
X26280768Y47547437D01*
X26280767Y47547437D01*
X26280765Y47547436D01*
X26029419Y47497440D01*
X25773141Y47497440D01*
X25521795Y47547436D01*
X25521793Y47547437D01*
X25521792Y47547437D01*
X25285025Y47645509D01*
X25071941Y47787887D01*
X25071938Y47787889D01*
X24890729Y47969098D01*
X24748349Y48182185D01*
X24650276Y48418955D01*
X24600280Y48670301D01*
X24600280Y48926579D01*
X24650276Y49177925D01*
X24748349Y49414695D01*
X24890729Y49627782D01*
X25071938Y49808991D01*
X25285025Y49951371D01*
X25521792Y50049443D01*
X25521793Y50049443D01*
X25521795Y50049444D01*
X25773141Y50099440D01*
X26029419Y50099440D01*
X26280765Y50049444D01*
X26280765Y50049444D01*
G37*
G36*
X57203825Y62759260D02*
X58578018Y62190050D01*
X58578020Y62190049D01*
X59011440Y61900447D01*
X59814765Y61363683D01*
X60866523Y60311925D01*
X60866525Y60311922D01*
X61154547Y59880867D01*
X61692890Y59075178D01*
X62262100Y57700985D01*
X62552280Y56242150D01*
X62552280Y54754730D01*
X62262100Y53295895D01*
X61804437Y52191001D01*
X61692889Y51921700D01*
X61449091Y51556830D01*
X60866523Y50684955D01*
X59814765Y49633197D01*
X59814762Y49633195D01*
X58578020Y48806831D01*
X58578019Y48806830D01*
X58578018Y48806830D01*
X57203825Y48237620D01*
X55744990Y47947440D01*
X54257570Y47947440D01*
X52798735Y48237620D01*
X51424542Y48806830D01*
X51424541Y48806830D01*
X51424540Y48806831D01*
X50187798Y49633195D01*
X50187795Y49633197D01*
X49136037Y50684955D01*
X48553469Y51556830D01*
X48309671Y51921700D01*
X48198123Y52191001D01*
X47740460Y53295895D01*
X47450280Y54754730D01*
X47450280Y56242150D01*
X47740460Y57700985D01*
X48309670Y59075178D01*
X48848014Y59880867D01*
X49136035Y60311922D01*
X49136037Y60311925D01*
X50187795Y61363683D01*
X50991120Y61900447D01*
X51424540Y62190049D01*
X51424542Y62190050D01*
X52798735Y62759260D01*
X54257570Y63049440D01*
X55744990Y63049440D01*
X57203825Y62759260D01*
X57203825Y62759260D01*
G37*
G36*
X117203825Y65509260D02*
X118578018Y64940050D01*
X118578020Y64940049D01*
X119798314Y64124675D01*
X119814765Y64113683D01*
X120866523Y63061925D01*
X120866525Y63061922D01*
X121449092Y62190049D01*
X121692890Y61825178D01*
X122262100Y60450985D01*
X122552280Y58992150D01*
X122552280Y57504730D01*
X122262100Y56045895D01*
X121727282Y54754731D01*
X121692889Y54671700D01*
X121558086Y54469953D01*
X120866523Y53434955D01*
X119814765Y52383197D01*
X119814762Y52383195D01*
X118578020Y51556831D01*
X118578019Y51556830D01*
X118578018Y51556830D01*
X117203825Y50987620D01*
X115744990Y50697440D01*
X114257570Y50697440D01*
X112798735Y50987620D01*
X111424542Y51556830D01*
X111424541Y51556830D01*
X111424540Y51556831D01*
X110187798Y52383195D01*
X110187795Y52383197D01*
X109136037Y53434955D01*
X108444474Y54469953D01*
X108309671Y54671700D01*
X108275278Y54754731D01*
X107740460Y56045895D01*
X107450280Y57504730D01*
X107450280Y58992150D01*
X107740460Y60450985D01*
X108309670Y61825178D01*
X108553469Y62190049D01*
X109136035Y63061922D01*
X109136037Y63061925D01*
X110187795Y64113683D01*
X110204246Y64124675D01*
X111424540Y64940049D01*
X111424542Y64940050D01*
X112798735Y65509260D01*
X114257570Y65799440D01*
X115744990Y65799440D01*
X117203825Y65509260D01*
X117203825Y65509260D01*
G37*
G36*
X6499532Y55470622D02*
X6499534Y55470621D01*
X6499535Y55470621D01*
X6872793Y55316013D01*
X6872794Y55316012D01*
X7208719Y55091554D01*
X7494394Y54805879D01*
X7494396Y54805876D01*
X7718853Y54469953D01*
X7873461Y54096695D01*
X7952280Y53700446D01*
X7952280Y53296434D01*
X7873461Y52900185D01*
X7718853Y52526927D01*
X7622814Y52383195D01*
X7494394Y52191001D01*
X7208719Y51905326D01*
X7208716Y51905324D01*
X6872793Y51680867D01*
X6499535Y51526259D01*
X6499534Y51526259D01*
X6499532Y51526258D01*
X6103287Y51447440D01*
X5699273Y51447440D01*
X5303028Y51526258D01*
X5303026Y51526259D01*
X5303025Y51526259D01*
X4929767Y51680867D01*
X4593844Y51905324D01*
X4593841Y51905326D01*
X4308166Y52191001D01*
X4179746Y52383195D01*
X4083707Y52526927D01*
X3929099Y52900185D01*
X3850280Y53296434D01*
X3850280Y53700446D01*
X3929099Y54096695D01*
X4083707Y54469953D01*
X4308164Y54805876D01*
X4308166Y54805879D01*
X4593841Y55091554D01*
X4929766Y55316012D01*
X4929767Y55316013D01*
X5303025Y55470621D01*
X5303026Y55470621D01*
X5303028Y55470622D01*
X5699273Y55549440D01*
X6103287Y55549440D01*
X6499532Y55470622D01*
X6499532Y55470622D01*
G37*
G36*
X30699532Y55470622D02*
X30699534Y55470621D01*
X30699535Y55470621D01*
X31072793Y55316013D01*
X31072794Y55316012D01*
X31408719Y55091554D01*
X31694394Y54805879D01*
X31694396Y54805876D01*
X31918853Y54469953D01*
X32073461Y54096695D01*
X32152280Y53700446D01*
X32152280Y53296434D01*
X32073461Y52900185D01*
X31918853Y52526927D01*
X31822814Y52383195D01*
X31694394Y52191001D01*
X31408719Y51905326D01*
X31408716Y51905324D01*
X31072793Y51680867D01*
X30699535Y51526259D01*
X30699534Y51526259D01*
X30699532Y51526258D01*
X30303287Y51447440D01*
X29899273Y51447440D01*
X29503028Y51526258D01*
X29503026Y51526259D01*
X29503025Y51526259D01*
X29129767Y51680867D01*
X28793844Y51905324D01*
X28793841Y51905326D01*
X28508166Y52191001D01*
X28379746Y52383195D01*
X28283707Y52526927D01*
X28129099Y52900185D01*
X28050280Y53296434D01*
X28050280Y53700446D01*
X28129099Y54096695D01*
X28283707Y54469953D01*
X28508164Y54805876D01*
X28508166Y54805879D01*
X28793841Y55091554D01*
X29129766Y55316012D01*
X29129767Y55316013D01*
X29503025Y55470621D01*
X29503026Y55470621D01*
X29503028Y55470622D01*
X29899273Y55549440D01*
X30303287Y55549440D01*
X30699532Y55470622D01*
X30699532Y55470622D01*
G37*
G36*
X30699532Y63670622D02*
X30699534Y63670621D01*
X30699535Y63670621D01*
X31072793Y63516013D01*
X31072794Y63516012D01*
X31408719Y63291554D01*
X31694394Y63005879D01*
X31694396Y63005876D01*
X31918853Y62669953D01*
X32073461Y62296695D01*
X32073462Y62296692D01*
X32152280Y61900447D01*
X32152280Y61496434D01*
X32073461Y61100185D01*
X31918853Y60726927D01*
X31918852Y60726926D01*
X31694394Y60391001D01*
X31408719Y60105326D01*
X31408716Y60105324D01*
X31072793Y59880867D01*
X30699535Y59726259D01*
X30699534Y59726259D01*
X30699532Y59726258D01*
X30303287Y59647440D01*
X29899273Y59647440D01*
X29503028Y59726258D01*
X29503026Y59726259D01*
X29503025Y59726259D01*
X29129767Y59880867D01*
X28793844Y60105324D01*
X28793841Y60105326D01*
X28508166Y60391001D01*
X28283708Y60726926D01*
X28283707Y60726927D01*
X28129099Y61100185D01*
X28050280Y61496434D01*
X28050280Y61900447D01*
X28129098Y62296692D01*
X28129099Y62296695D01*
X28283707Y62669953D01*
X28508164Y63005876D01*
X28508166Y63005879D01*
X28793841Y63291554D01*
X29129766Y63516012D01*
X29129767Y63516013D01*
X29503025Y63670621D01*
X29503026Y63670621D01*
X29503028Y63670622D01*
X29899273Y63749440D01*
X30303287Y63749440D01*
X30699532Y63670622D01*
X30699532Y63670622D01*
G37*
G36*
X6499532Y63670622D02*
X6499534Y63670621D01*
X6499535Y63670621D01*
X6872793Y63516013D01*
X6872794Y63516012D01*
X7208719Y63291554D01*
X7494394Y63005879D01*
X7494396Y63005876D01*
X7718853Y62669953D01*
X7873461Y62296695D01*
X7873462Y62296692D01*
X7952280Y61900447D01*
X7952280Y61496434D01*
X7873461Y61100185D01*
X7718853Y60726927D01*
X7718852Y60726926D01*
X7494394Y60391001D01*
X7208719Y60105326D01*
X7208716Y60105324D01*
X6872793Y59880867D01*
X6499535Y59726259D01*
X6499534Y59726259D01*
X6499532Y59726258D01*
X6103287Y59647440D01*
X5699273Y59647440D01*
X5303028Y59726258D01*
X5303026Y59726259D01*
X5303025Y59726259D01*
X4929767Y59880867D01*
X4593844Y60105324D01*
X4593841Y60105326D01*
X4308166Y60391001D01*
X4083708Y60726926D01*
X4083707Y60726927D01*
X3929099Y61100185D01*
X3850280Y61496434D01*
X3850280Y61900447D01*
X3929098Y62296692D01*
X3929099Y62296695D01*
X4083707Y62669953D01*
X4308164Y63005876D01*
X4308166Y63005879D01*
X4593841Y63291554D01*
X4929766Y63516012D01*
X4929767Y63516013D01*
X5303025Y63670621D01*
X5303026Y63670621D01*
X5303028Y63670622D01*
X5699273Y63749440D01*
X6103287Y63749440D01*
X6499532Y63670622D01*
X6499532Y63670622D01*
G37*
G36*
X10680765Y67649444D02*
X10680767Y67649443D01*
X10680768Y67649443D01*
X10917535Y67551371D01*
X11130622Y67408991D01*
X11311831Y67227782D01*
X11454211Y67014695D01*
X11552284Y66777925D01*
X11602280Y66526579D01*
X11602280Y66270301D01*
X11552284Y66018955D01*
X11454211Y65782185D01*
X11311831Y65569098D01*
X11130622Y65387889D01*
X11130619Y65387887D01*
X10917535Y65245509D01*
X10680768Y65147437D01*
X10680767Y65147437D01*
X10680765Y65147436D01*
X10429419Y65097440D01*
X10173141Y65097440D01*
X9921795Y65147436D01*
X9921793Y65147437D01*
X9921792Y65147437D01*
X9685025Y65245509D01*
X9471941Y65387887D01*
X9471938Y65387889D01*
X9290729Y65569098D01*
X9148349Y65782185D01*
X9050276Y66018955D01*
X9000280Y66270301D01*
X9000280Y66526579D01*
X9050276Y66777925D01*
X9148349Y67014695D01*
X9290729Y67227782D01*
X9471938Y67408991D01*
X9685025Y67551371D01*
X9921792Y67649443D01*
X9921793Y67649443D01*
X9921795Y67649444D01*
X10173141Y67699440D01*
X10429419Y67699440D01*
X10680765Y67649444D01*
X10680765Y67649444D01*
G37*
G36*
X26080765Y67649444D02*
X26080767Y67649443D01*
X26080768Y67649443D01*
X26317535Y67551371D01*
X26530622Y67408991D01*
X26711831Y67227782D01*
X26854211Y67014695D01*
X26952284Y66777925D01*
X27002280Y66526579D01*
X27002280Y66270301D01*
X26952284Y66018955D01*
X26854211Y65782185D01*
X26711831Y65569098D01*
X26530622Y65387889D01*
X26530619Y65387887D01*
X26317535Y65245509D01*
X26080768Y65147437D01*
X26080767Y65147437D01*
X26080765Y65147436D01*
X25829419Y65097440D01*
X25573141Y65097440D01*
X25321795Y65147436D01*
X25321793Y65147437D01*
X25321792Y65147437D01*
X25085025Y65245509D01*
X24871941Y65387887D01*
X24871938Y65387889D01*
X24690729Y65569098D01*
X24548349Y65782185D01*
X24450276Y66018955D01*
X24400280Y66270301D01*
X24400280Y66526579D01*
X24450276Y66777925D01*
X24548349Y67014695D01*
X24690729Y67227782D01*
X24871938Y67408991D01*
X25085025Y67551371D01*
X25321792Y67649443D01*
X25321793Y67649443D01*
X25321795Y67649444D01*
X25573141Y67699440D01*
X25829419Y67699440D01*
X26080765Y67649444D01*
X26080765Y67649444D01*
G37*
G36*
X30280765Y67649444D02*
X30280767Y67649443D01*
X30280768Y67649443D01*
X30517535Y67551371D01*
X30730622Y67408991D01*
X30911831Y67227782D01*
X31054211Y67014695D01*
X31152284Y66777925D01*
X31202280Y66526579D01*
X31202280Y66270301D01*
X31152284Y66018955D01*
X31054211Y65782185D01*
X30911831Y65569098D01*
X30730622Y65387889D01*
X30730619Y65387887D01*
X30517535Y65245509D01*
X30280768Y65147437D01*
X30280767Y65147437D01*
X30280765Y65147436D01*
X30029419Y65097440D01*
X29773141Y65097440D01*
X29521795Y65147436D01*
X29521793Y65147437D01*
X29521792Y65147437D01*
X29285025Y65245509D01*
X29071941Y65387887D01*
X29071938Y65387889D01*
X28890729Y65569098D01*
X28748349Y65782185D01*
X28650276Y66018955D01*
X28600280Y66270301D01*
X28600280Y66526579D01*
X28650276Y66777925D01*
X28748349Y67014695D01*
X28890729Y67227782D01*
X29071938Y67408991D01*
X29285025Y67551371D01*
X29521792Y67649443D01*
X29521793Y67649443D01*
X29521795Y67649444D01*
X29773141Y67699440D01*
X30029419Y67699440D01*
X30280765Y67649444D01*
X30280765Y67649444D01*
G37*
G36*
X6480765Y67649444D02*
X6480767Y67649443D01*
X6480768Y67649443D01*
X6717535Y67551371D01*
X6930622Y67408991D01*
X7111831Y67227782D01*
X7254211Y67014695D01*
X7352284Y66777925D01*
X7402280Y66526579D01*
X7402280Y66270301D01*
X7352284Y66018955D01*
X7254211Y65782185D01*
X7111831Y65569098D01*
X6930622Y65387889D01*
X6930619Y65387887D01*
X6717535Y65245509D01*
X6480768Y65147437D01*
X6480767Y65147437D01*
X6480765Y65147436D01*
X6229419Y65097440D01*
X5973141Y65097440D01*
X5721795Y65147436D01*
X5721793Y65147437D01*
X5721792Y65147437D01*
X5485025Y65245509D01*
X5271941Y65387887D01*
X5271938Y65387889D01*
X5090729Y65569098D01*
X4948349Y65782185D01*
X4850276Y66018955D01*
X4800280Y66270301D01*
X4800280Y66526579D01*
X4850276Y66777925D01*
X4948349Y67014695D01*
X5090729Y67227782D01*
X5271938Y67408991D01*
X5485025Y67551371D01*
X5721792Y67649443D01*
X5721793Y67649443D01*
X5721795Y67649444D01*
X5973141Y67699440D01*
X6229419Y67699440D01*
X6480765Y67649444D01*
X6480765Y67649444D01*
G37*
G36*
X10680765Y71849444D02*
X10680767Y71849443D01*
X10680768Y71849443D01*
X10917535Y71751371D01*
X11130622Y71608991D01*
X11311831Y71427782D01*
X11454211Y71214695D01*
X11552284Y70977925D01*
X11602280Y70726579D01*
X11602280Y70470301D01*
X11552284Y70218955D01*
X11454211Y69982185D01*
X11311831Y69769098D01*
X11130622Y69587889D01*
X11130619Y69587887D01*
X10917535Y69445509D01*
X10680768Y69347437D01*
X10680767Y69347437D01*
X10680765Y69347436D01*
X10429419Y69297440D01*
X10173141Y69297440D01*
X9921795Y69347436D01*
X9921793Y69347437D01*
X9921792Y69347437D01*
X9685025Y69445509D01*
X9471941Y69587887D01*
X9471938Y69587889D01*
X9290729Y69769098D01*
X9148349Y69982185D01*
X9050276Y70218955D01*
X9000280Y70470301D01*
X9000280Y70726579D01*
X9050276Y70977925D01*
X9148349Y71214695D01*
X9290729Y71427782D01*
X9471938Y71608991D01*
X9685025Y71751371D01*
X9921792Y71849443D01*
X9921793Y71849443D01*
X9921795Y71849444D01*
X10173141Y71899440D01*
X10429419Y71899440D01*
X10680765Y71849444D01*
X10680765Y71849444D01*
G37*
G36*
X26080765Y71849444D02*
X26080767Y71849443D01*
X26080768Y71849443D01*
X26317535Y71751371D01*
X26530622Y71608991D01*
X26711831Y71427782D01*
X26854211Y71214695D01*
X26952284Y70977925D01*
X27002280Y70726579D01*
X27002280Y70470301D01*
X26952284Y70218955D01*
X26854211Y69982185D01*
X26711831Y69769098D01*
X26530622Y69587889D01*
X26530619Y69587887D01*
X26317535Y69445509D01*
X26080768Y69347437D01*
X26080767Y69347437D01*
X26080765Y69347436D01*
X25829419Y69297440D01*
X25573141Y69297440D01*
X25321795Y69347436D01*
X25321793Y69347437D01*
X25321792Y69347437D01*
X25085025Y69445509D01*
X24871941Y69587887D01*
X24871938Y69587889D01*
X24690729Y69769098D01*
X24548349Y69982185D01*
X24450276Y70218955D01*
X24400280Y70470301D01*
X24400280Y70726579D01*
X24450276Y70977925D01*
X24548349Y71214695D01*
X24690729Y71427782D01*
X24871938Y71608991D01*
X25085025Y71751371D01*
X25321792Y71849443D01*
X25321793Y71849443D01*
X25321795Y71849444D01*
X25573141Y71899440D01*
X25829419Y71899440D01*
X26080765Y71849444D01*
X26080765Y71849444D01*
G37*
G36*
X30280765Y71849444D02*
X30280767Y71849443D01*
X30280768Y71849443D01*
X30517535Y71751371D01*
X30730622Y71608991D01*
X30911831Y71427782D01*
X31054211Y71214695D01*
X31152284Y70977925D01*
X31202280Y70726579D01*
X31202280Y70470301D01*
X31152284Y70218955D01*
X31054211Y69982185D01*
X30911831Y69769098D01*
X30730622Y69587889D01*
X30730619Y69587887D01*
X30517535Y69445509D01*
X30280768Y69347437D01*
X30280767Y69347437D01*
X30280765Y69347436D01*
X30029419Y69297440D01*
X29773141Y69297440D01*
X29521795Y69347436D01*
X29521793Y69347437D01*
X29521792Y69347437D01*
X29285025Y69445509D01*
X29071941Y69587887D01*
X29071938Y69587889D01*
X28890729Y69769098D01*
X28748349Y69982185D01*
X28650276Y70218955D01*
X28600280Y70470301D01*
X28600280Y70726579D01*
X28650276Y70977925D01*
X28748349Y71214695D01*
X28890729Y71427782D01*
X29071938Y71608991D01*
X29285025Y71751371D01*
X29521792Y71849443D01*
X29521793Y71849443D01*
X29521795Y71849444D01*
X29773141Y71899440D01*
X30029419Y71899440D01*
X30280765Y71849444D01*
X30280765Y71849444D01*
G37*
G36*
X6480765Y71849444D02*
X6480767Y71849443D01*
X6480768Y71849443D01*
X6717535Y71751371D01*
X6930622Y71608991D01*
X7111831Y71427782D01*
X7254211Y71214695D01*
X7352284Y70977925D01*
X7402280Y70726579D01*
X7402280Y70470301D01*
X7352284Y70218955D01*
X7254211Y69982185D01*
X7111831Y69769098D01*
X6930622Y69587889D01*
X6930619Y69587887D01*
X6717535Y69445509D01*
X6480768Y69347437D01*
X6480767Y69347437D01*
X6480765Y69347436D01*
X6229419Y69297440D01*
X5973141Y69297440D01*
X5721795Y69347436D01*
X5721793Y69347437D01*
X5721792Y69347437D01*
X5485025Y69445509D01*
X5271941Y69587887D01*
X5271938Y69587889D01*
X5090729Y69769098D01*
X4948349Y69982185D01*
X4850276Y70218955D01*
X4800280Y70470301D01*
X4800280Y70726579D01*
X4850276Y70977925D01*
X4948349Y71214695D01*
X5090729Y71427782D01*
X5271938Y71608991D01*
X5485025Y71751371D01*
X5721792Y71849443D01*
X5721793Y71849443D01*
X5721795Y71849444D01*
X5973141Y71899440D01*
X6229419Y71899440D01*
X6480765Y71849444D01*
X6480765Y71849444D01*
G37*
G36*
X57203825Y85259260D02*
X58578018Y84690050D01*
X58578020Y84690049D01*
X59124085Y84325180D01*
X59814765Y83863683D01*
X60866523Y82811925D01*
X60866525Y82811922D01*
X61488636Y81880867D01*
X61692890Y81575178D01*
X62262100Y80200985D01*
X62552280Y78742150D01*
X62552280Y77254730D01*
X62262100Y75795895D01*
X61795864Y74670303D01*
X61692889Y74421700D01*
X61108725Y73547436D01*
X60866523Y73184955D01*
X59814765Y72133197D01*
X59814762Y72133195D01*
X58578020Y71306831D01*
X58578019Y71306830D01*
X58578018Y71306830D01*
X57203825Y70737620D01*
X55744990Y70447440D01*
X54257570Y70447440D01*
X52798735Y70737620D01*
X51424542Y71306830D01*
X51424541Y71306830D01*
X51424540Y71306831D01*
X50187798Y72133195D01*
X50187795Y72133197D01*
X49136037Y73184955D01*
X48893835Y73547436D01*
X48309671Y74421700D01*
X48206696Y74670303D01*
X47740460Y75795895D01*
X47450280Y77254730D01*
X47450280Y78742150D01*
X47740460Y80200985D01*
X48309670Y81575178D01*
X48513925Y81880867D01*
X49136035Y82811922D01*
X49136037Y82811925D01*
X50187795Y83863683D01*
X50878475Y84325180D01*
X51424540Y84690049D01*
X51424542Y84690050D01*
X52798735Y85259260D01*
X54257570Y85549440D01*
X55744990Y85549440D01*
X57203825Y85259260D01*
X57203825Y85259260D01*
G37*
G36*
X117203825Y88009260D02*
X118560177Y87447440D01*
X118578020Y87440049D01*
X119798314Y86624675D01*
X119814765Y86613683D01*
X120866523Y85561925D01*
X120866525Y85561922D01*
X121462519Y84669954D01*
X121692890Y84325178D01*
X122262100Y82950985D01*
X122552280Y81492150D01*
X122552280Y80004730D01*
X122262100Y78545895D01*
X121692890Y77171702D01*
X120866523Y75934955D01*
X119814765Y74883197D01*
X119814762Y74883195D01*
X118578020Y74056831D01*
X118578019Y74056830D01*
X118578018Y74056830D01*
X117203825Y73487620D01*
X115744990Y73197440D01*
X114257570Y73197440D01*
X112798735Y73487620D01*
X111424542Y74056830D01*
X111424541Y74056830D01*
X111424540Y74056831D01*
X110187798Y74883195D01*
X110187795Y74883197D01*
X109136037Y75934955D01*
X108309670Y77171702D01*
X107740460Y78545895D01*
X107450280Y80004730D01*
X107450280Y81492150D01*
X107740460Y82950985D01*
X108309670Y84325178D01*
X108540042Y84669954D01*
X109136035Y85561922D01*
X109136037Y85561925D01*
X110187795Y86613683D01*
X110204246Y86624675D01*
X111424540Y87440049D01*
X111442383Y87447440D01*
X112798735Y88009260D01*
X114257570Y88299440D01*
X115744990Y88299440D01*
X117203825Y88009260D01*
X117203825Y88009260D01*
G37*
G36*
X26080765Y76049444D02*
X26080767Y76049443D01*
X26080768Y76049443D01*
X26317535Y75951371D01*
X26530622Y75808991D01*
X26711831Y75627782D01*
X26854211Y75414695D01*
X26952284Y75177925D01*
X27002280Y74926579D01*
X27002280Y74670301D01*
X26952284Y74418955D01*
X26854211Y74182185D01*
X26711831Y73969098D01*
X26530622Y73787889D01*
X26530619Y73787887D01*
X26317535Y73645509D01*
X26080768Y73547437D01*
X26080767Y73547437D01*
X26080765Y73547436D01*
X25829419Y73497440D01*
X25573141Y73497440D01*
X25321795Y73547436D01*
X25321793Y73547437D01*
X25321792Y73547437D01*
X25085025Y73645509D01*
X24871941Y73787887D01*
X24871938Y73787889D01*
X24690729Y73969098D01*
X24548349Y74182185D01*
X24450276Y74418955D01*
X24400280Y74670301D01*
X24400280Y74926579D01*
X24450276Y75177925D01*
X24548349Y75414695D01*
X24690729Y75627782D01*
X24871938Y75808991D01*
X25085025Y75951371D01*
X25321792Y76049443D01*
X25321793Y76049443D01*
X25321795Y76049444D01*
X25573141Y76099440D01*
X25829419Y76099440D01*
X26080765Y76049444D01*
X26080765Y76049444D01*
G37*
G36*
X30280765Y76049444D02*
X30280767Y76049443D01*
X30280768Y76049443D01*
X30517535Y75951371D01*
X30730622Y75808991D01*
X30911831Y75627782D01*
X31054211Y75414695D01*
X31152284Y75177925D01*
X31202280Y74926579D01*
X31202280Y74670301D01*
X31152284Y74418955D01*
X31054211Y74182185D01*
X30911831Y73969098D01*
X30730622Y73787889D01*
X30730619Y73787887D01*
X30517535Y73645509D01*
X30280768Y73547437D01*
X30280767Y73547437D01*
X30280765Y73547436D01*
X30029419Y73497440D01*
X29773141Y73497440D01*
X29521795Y73547436D01*
X29521793Y73547437D01*
X29521792Y73547437D01*
X29285025Y73645509D01*
X29071941Y73787887D01*
X29071938Y73787889D01*
X28890729Y73969098D01*
X28748349Y74182185D01*
X28650276Y74418955D01*
X28600280Y74670301D01*
X28600280Y74926579D01*
X28650276Y75177925D01*
X28748349Y75414695D01*
X28890729Y75627782D01*
X29071938Y75808991D01*
X29285025Y75951371D01*
X29521792Y76049443D01*
X29521793Y76049443D01*
X29521795Y76049444D01*
X29773141Y76099440D01*
X30029419Y76099440D01*
X30280765Y76049444D01*
X30280765Y76049444D01*
G37*
G36*
X10680765Y76049444D02*
X10680767Y76049443D01*
X10680768Y76049443D01*
X10917535Y75951371D01*
X11130622Y75808991D01*
X11311831Y75627782D01*
X11454211Y75414695D01*
X11552284Y75177925D01*
X11602280Y74926579D01*
X11602280Y74670301D01*
X11552284Y74418955D01*
X11454211Y74182185D01*
X11311831Y73969098D01*
X11130622Y73787889D01*
X11130619Y73787887D01*
X10917535Y73645509D01*
X10680768Y73547437D01*
X10680767Y73547437D01*
X10680765Y73547436D01*
X10429419Y73497440D01*
X10173141Y73497440D01*
X9921795Y73547436D01*
X9921793Y73547437D01*
X9921792Y73547437D01*
X9685025Y73645509D01*
X9471941Y73787887D01*
X9471938Y73787889D01*
X9290729Y73969098D01*
X9148349Y74182185D01*
X9050276Y74418955D01*
X9000280Y74670301D01*
X9000280Y74926579D01*
X9050276Y75177925D01*
X9148349Y75414695D01*
X9290729Y75627782D01*
X9471938Y75808991D01*
X9685025Y75951371D01*
X9921792Y76049443D01*
X9921793Y76049443D01*
X9921795Y76049444D01*
X10173141Y76099440D01*
X10429419Y76099440D01*
X10680765Y76049444D01*
X10680765Y76049444D01*
G37*
G36*
X6480765Y76049444D02*
X6480767Y76049443D01*
X6480768Y76049443D01*
X6717535Y75951371D01*
X6930622Y75808991D01*
X7111831Y75627782D01*
X7254211Y75414695D01*
X7352284Y75177925D01*
X7402280Y74926579D01*
X7402280Y74670301D01*
X7352284Y74418955D01*
X7254211Y74182185D01*
X7111831Y73969098D01*
X6930622Y73787889D01*
X6930619Y73787887D01*
X6717535Y73645509D01*
X6480768Y73547437D01*
X6480767Y73547437D01*
X6480765Y73547436D01*
X6229419Y73497440D01*
X5973141Y73497440D01*
X5721795Y73547436D01*
X5721793Y73547437D01*
X5721792Y73547437D01*
X5485025Y73645509D01*
X5271941Y73787887D01*
X5271938Y73787889D01*
X5090729Y73969098D01*
X4948349Y74182185D01*
X4850276Y74418955D01*
X4800280Y74670301D01*
X4800280Y74926579D01*
X4850276Y75177925D01*
X4948349Y75414695D01*
X5090729Y75627782D01*
X5271938Y75808991D01*
X5485025Y75951371D01*
X5721792Y76049443D01*
X5721793Y76049443D01*
X5721795Y76049444D01*
X5973141Y76099440D01*
X6229419Y76099440D01*
X6480765Y76049444D01*
X6480765Y76049444D01*
G37*
G36*
X10680765Y80249444D02*
X10680767Y80249443D01*
X10680768Y80249443D01*
X10797756Y80200985D01*
X10917535Y80151371D01*
X11130622Y80008991D01*
X11311831Y79827782D01*
X11454211Y79614695D01*
X11552284Y79377925D01*
X11602280Y79126579D01*
X11602280Y78870301D01*
X11552284Y78618955D01*
X11454211Y78382185D01*
X11311831Y78169098D01*
X11130622Y77987889D01*
X11130619Y77987887D01*
X10917535Y77845509D01*
X10680768Y77747437D01*
X10680767Y77747437D01*
X10680765Y77747436D01*
X10429419Y77697440D01*
X10173141Y77697440D01*
X9921795Y77747436D01*
X9921793Y77747437D01*
X9921792Y77747437D01*
X9685025Y77845509D01*
X9471941Y77987887D01*
X9471938Y77987889D01*
X9290729Y78169098D01*
X9148349Y78382185D01*
X9050276Y78618955D01*
X9000280Y78870301D01*
X9000280Y79126579D01*
X9050276Y79377925D01*
X9148349Y79614695D01*
X9290729Y79827782D01*
X9471938Y80008991D01*
X9685025Y80151371D01*
X9804804Y80200985D01*
X9921792Y80249443D01*
X9921793Y80249443D01*
X9921795Y80249444D01*
X10173141Y80299440D01*
X10429419Y80299440D01*
X10680765Y80249444D01*
X10680765Y80249444D01*
G37*
G36*
X6480765Y80249444D02*
X6480767Y80249443D01*
X6480768Y80249443D01*
X6597756Y80200985D01*
X6717535Y80151371D01*
X6930622Y80008991D01*
X7111831Y79827782D01*
X7254211Y79614695D01*
X7352284Y79377925D01*
X7402280Y79126579D01*
X7402280Y78870301D01*
X7352284Y78618955D01*
X7254211Y78382185D01*
X7111831Y78169098D01*
X6930622Y77987889D01*
X6930619Y77987887D01*
X6717535Y77845509D01*
X6480768Y77747437D01*
X6480767Y77747437D01*
X6480765Y77747436D01*
X6229419Y77697440D01*
X5973141Y77697440D01*
X5721795Y77747436D01*
X5721793Y77747437D01*
X5721792Y77747437D01*
X5485025Y77845509D01*
X5271941Y77987887D01*
X5271938Y77987889D01*
X5090729Y78169098D01*
X4948349Y78382185D01*
X4850276Y78618955D01*
X4800280Y78870301D01*
X4800280Y79126579D01*
X4850276Y79377925D01*
X4948349Y79614695D01*
X5090729Y79827782D01*
X5271938Y80008991D01*
X5485025Y80151371D01*
X5604804Y80200985D01*
X5721792Y80249443D01*
X5721793Y80249443D01*
X5721795Y80249444D01*
X5973141Y80299440D01*
X6229419Y80299440D01*
X6480765Y80249444D01*
X6480765Y80249444D01*
G37*
G36*
X26080765Y80249444D02*
X26080767Y80249443D01*
X26080768Y80249443D01*
X26197756Y80200985D01*
X26317535Y80151371D01*
X26530622Y80008991D01*
X26711831Y79827782D01*
X26854211Y79614695D01*
X26952284Y79377925D01*
X27002280Y79126579D01*
X27002280Y78870301D01*
X26952284Y78618955D01*
X26854211Y78382185D01*
X26711831Y78169098D01*
X26530622Y77987889D01*
X26530619Y77987887D01*
X26317535Y77845509D01*
X26080768Y77747437D01*
X26080767Y77747437D01*
X26080765Y77747436D01*
X25829419Y77697440D01*
X25573141Y77697440D01*
X25321795Y77747436D01*
X25321793Y77747437D01*
X25321792Y77747437D01*
X25085025Y77845509D01*
X24871941Y77987887D01*
X24871938Y77987889D01*
X24690729Y78169098D01*
X24548349Y78382185D01*
X24450276Y78618955D01*
X24400280Y78870301D01*
X24400280Y79126579D01*
X24450276Y79377925D01*
X24548349Y79614695D01*
X24690729Y79827782D01*
X24871938Y80008991D01*
X25085025Y80151371D01*
X25204804Y80200985D01*
X25321792Y80249443D01*
X25321793Y80249443D01*
X25321795Y80249444D01*
X25573141Y80299440D01*
X25829419Y80299440D01*
X26080765Y80249444D01*
X26080765Y80249444D01*
G37*
G36*
X30280765Y80249444D02*
X30280767Y80249443D01*
X30280768Y80249443D01*
X30397756Y80200985D01*
X30517535Y80151371D01*
X30730622Y80008991D01*
X30911831Y79827782D01*
X31054211Y79614695D01*
X31152284Y79377925D01*
X31202280Y79126579D01*
X31202280Y78870301D01*
X31152284Y78618955D01*
X31054211Y78382185D01*
X30911831Y78169098D01*
X30730622Y77987889D01*
X30730619Y77987887D01*
X30517535Y77845509D01*
X30280768Y77747437D01*
X30280767Y77747437D01*
X30280765Y77747436D01*
X30029419Y77697440D01*
X29773141Y77697440D01*
X29521795Y77747436D01*
X29521793Y77747437D01*
X29521792Y77747437D01*
X29285025Y77845509D01*
X29071941Y77987887D01*
X29071938Y77987889D01*
X28890729Y78169098D01*
X28748349Y78382185D01*
X28650276Y78618955D01*
X28600280Y78870301D01*
X28600280Y79126579D01*
X28650276Y79377925D01*
X28748349Y79614695D01*
X28890729Y79827782D01*
X29071938Y80008991D01*
X29285025Y80151371D01*
X29404804Y80200985D01*
X29521792Y80249443D01*
X29521793Y80249443D01*
X29521795Y80249444D01*
X29773141Y80299440D01*
X30029419Y80299440D01*
X30280765Y80249444D01*
X30280765Y80249444D01*
G37*
G36*
X6499532Y85670622D02*
X6499534Y85670621D01*
X6499535Y85670621D01*
X6872793Y85516013D01*
X6872794Y85516012D01*
X7208719Y85291554D01*
X7494394Y85005879D01*
X7494396Y85005876D01*
X7718853Y84669953D01*
X7873461Y84296695D01*
X7952280Y83900446D01*
X7952280Y83496434D01*
X7873461Y83100185D01*
X7718853Y82726927D01*
X7718852Y82726926D01*
X7494394Y82391001D01*
X7208719Y82105326D01*
X7208716Y82105324D01*
X6872793Y81880867D01*
X6499535Y81726259D01*
X6499534Y81726259D01*
X6499532Y81726258D01*
X6103287Y81647440D01*
X5699273Y81647440D01*
X5303028Y81726258D01*
X5303026Y81726259D01*
X5303025Y81726259D01*
X4929767Y81880867D01*
X4593844Y82105324D01*
X4593841Y82105326D01*
X4308166Y82391001D01*
X4083708Y82726926D01*
X4083707Y82726927D01*
X3929099Y83100185D01*
X3850280Y83496434D01*
X3850280Y83900446D01*
X3929099Y84296695D01*
X4083707Y84669953D01*
X4308164Y85005876D01*
X4308166Y85005879D01*
X4593841Y85291554D01*
X4929766Y85516012D01*
X4929767Y85516013D01*
X5303025Y85670621D01*
X5303026Y85670621D01*
X5303028Y85670622D01*
X5699273Y85749440D01*
X6103287Y85749440D01*
X6499532Y85670622D01*
X6499532Y85670622D01*
G37*
G36*
X30699532Y85670622D02*
X30699534Y85670621D01*
X30699535Y85670621D01*
X31072793Y85516013D01*
X31072794Y85516012D01*
X31408719Y85291554D01*
X31694394Y85005879D01*
X31694396Y85005876D01*
X31918853Y84669953D01*
X32073461Y84296695D01*
X32152280Y83900446D01*
X32152280Y83496434D01*
X32073461Y83100185D01*
X31918853Y82726927D01*
X31918852Y82726926D01*
X31694394Y82391001D01*
X31408719Y82105326D01*
X31408716Y82105324D01*
X31072793Y81880867D01*
X30699535Y81726259D01*
X30699534Y81726259D01*
X30699532Y81726258D01*
X30303287Y81647440D01*
X29899273Y81647440D01*
X29503028Y81726258D01*
X29503026Y81726259D01*
X29503025Y81726259D01*
X29129767Y81880867D01*
X28793844Y82105324D01*
X28793841Y82105326D01*
X28508166Y82391001D01*
X28283708Y82726926D01*
X28283707Y82726927D01*
X28129099Y83100185D01*
X28050280Y83496434D01*
X28050280Y83900446D01*
X28129099Y84296695D01*
X28283707Y84669953D01*
X28508164Y85005876D01*
X28508166Y85005879D01*
X28793841Y85291554D01*
X29129766Y85516012D01*
X29129767Y85516013D01*
X29503025Y85670621D01*
X29503026Y85670621D01*
X29503028Y85670622D01*
X29899273Y85749440D01*
X30303287Y85749440D01*
X30699532Y85670622D01*
X30699532Y85670622D01*
G37*
G36*
X140745376Y92451407D02*
X140745378Y92451406D01*
X140745379Y92451406D01*
X141209632Y92259107D01*
X141625564Y91981190D01*
X141627451Y91979929D01*
X141982769Y91624611D01*
X141982771Y91624608D01*
X142261947Y91206792D01*
X142454246Y90742539D01*
X142552280Y90249692D01*
X142552280Y89747188D01*
X142454246Y89254341D01*
X142261947Y88790088D01*
X141984030Y88374156D01*
X141982769Y88372269D01*
X141627451Y88016951D01*
X141627448Y88016949D01*
X141209632Y87737773D01*
X140745379Y87545474D01*
X140745378Y87545474D01*
X140745376Y87545473D01*
X140252533Y87447440D01*
X139750027Y87447440D01*
X139257184Y87545473D01*
X139257182Y87545474D01*
X139257181Y87545474D01*
X138792928Y87737773D01*
X138375112Y88016949D01*
X138375109Y88016951D01*
X138019791Y88372269D01*
X138018530Y88374156D01*
X137740613Y88790088D01*
X137548314Y89254341D01*
X137450280Y89747188D01*
X137450280Y90249692D01*
X137548314Y90742539D01*
X137740613Y91206792D01*
X138019789Y91624608D01*
X138019791Y91624611D01*
X138375109Y91979929D01*
X138376996Y91981190D01*
X138792928Y92259107D01*
X139257181Y92451406D01*
X139257182Y92451406D01*
X139257184Y92451407D01*
X139750027Y92549440D01*
X140252533Y92549440D01*
X140745376Y92451407D01*
X140745376Y92451407D01*
G37*
G36*
X745376Y92451407D02*
X745378Y92451406D01*
X745379Y92451406D01*
X1209632Y92259107D01*
X1625564Y91981190D01*
X1627451Y91979929D01*
X1982769Y91624611D01*
X1982771Y91624608D01*
X2261947Y91206792D01*
X2454246Y90742539D01*
X2552280Y90249692D01*
X2552280Y89747188D01*
X2454246Y89254341D01*
X2261947Y88790088D01*
X1984030Y88374156D01*
X1982769Y88372269D01*
X1627451Y88016951D01*
X1627448Y88016949D01*
X1209632Y87737773D01*
X745379Y87545474D01*
X745378Y87545474D01*
X745376Y87545473D01*
X252533Y87447440D01*
X-249973Y87447440D01*
X-742816Y87545473D01*
X-742818Y87545474D01*
X-742819Y87545474D01*
X-1207072Y87737773D01*
X-1624888Y88016949D01*
X-1624891Y88016951D01*
X-1980209Y88372269D01*
X-1981470Y88374156D01*
X-2259387Y88790088D01*
X-2451686Y89254341D01*
X-2549720Y89747188D01*
X-2549720Y90249692D01*
X-2451686Y90742539D01*
X-2259387Y91206792D01*
X-1980211Y91624608D01*
X-1980209Y91624611D01*
X-1624891Y91979929D01*
X-1623004Y91981190D01*
X-1207072Y92259107D01*
X-742819Y92451406D01*
X-742818Y92451406D01*
X-742816Y92451407D01*
X-249973Y92549440D01*
X252533Y92549440D01*
X745376Y92451407D01*
X745376Y92451407D01*
G37*
M02*
